(kicad_pcb
	(version 20260206)
	(generator "pcbnew")
	(generator_version "10.0")
	(general
		(thickness 1.6)
		(legacy_teardrops no)
	)
	(paper "A4")
	(title_block
		(title "dpb — 14545-sa.0730WZS0815.brd")
		(comment 1 "Honey Badger (Wiwynn) / footprints 872-875 of 1066")
	)
	(layers
		(0 "F.Cu" signal "TOP")
		(4 "In1.Cu" signal "L2GND")
		(6 "In2.Cu" signal "L3")
		(8 "In3.Cu" signal "L4VCC")
		(10 "In4.Cu" signal "L5VCC")
		(12 "In5.Cu" signal "L6")
		(14 "In6.Cu" signal "L7GND")
		(2 "B.Cu" signal "BOTTOM")
		(9 "F.Adhes" user "F.Adhesive")
		(11 "B.Adhes" user "B.Adhesive")
		(13 "F.Paste" user "Package Geometry/Pastemask Top")
		(15 "B.Paste" user "Package Geometry/Pastemask Bottom")
		(5 "F.SilkS" user "Ref Des/Silkscreen Top")
		(7 "B.SilkS" user "Ref Des/Silkscreen Bottom")
		(1 "F.Mask" user "Board Geometry/Soldermask Top")
		(3 "B.Mask" user "Board Geometry/Soldermask Bottom")
		(17 "Dwgs.User" user "User.Drawings")
		(19 "Cmts.User" user "User.Comments")
		(21 "Eco1.User" user "User.Eco1")
		(23 "Eco2.User" user "User.Eco2")
		(25 "Edge.Cuts" user "Board Geometry/Outline")
		(27 "Margin" user)
		(31 "F.CrtYd" user "Package Geometry/Place Bound Top")
		(29 "B.CrtYd" user "Package Geometry/Place Bound Bottom")
		(35 "F.Fab" user "Ref Des/Assembly Top")
		(33 "B.Fab" user "Ref Des/Assembly Bottom")
	)
	(footprint ""
		(layer "F.Cu")
		(at 43.942 -234.3658 90)
		(property "Reference" "R400"
			(at 0 0 90)
			(layer "F.SilkS")
			(hide yes)
			(effects
				(font
					(size 1.27 1.27)
				)
			)
		)
		(property "Value" "0R2J-2-GP"
			(at 0.064008 -3.993896 90)
			(unlocked yes)
			(layer "F.Fab")
			(hide yes)
			(effects
				(font
					(size 1.016 1.016)
					(thickness 0.1524)
				)
			)
		)
		(property "Device Type" "R402H16"
			(at 0.064008 -5.517896 90)
			(unlocked yes)
			(layer "F.Fab")
			(hide yes)
			(effects
				(font
					(size 1.016 1.016)
					(thickness 0.1524)
				)
			)
		)
		(duplicate_pad_numbers_are_jumpers no)
		(fp_line
			(start 0.508 -0.9398)
			(end -0.508 -0.9398)
			(stroke
				(width 0.1524)
				(type default)
			)
			(layer "F.SilkS")
		)
		(fp_line
			(start -0.508 -0.9398)
			(end -0.508 0.9398)
			(stroke
				(width 0.1524)
				(type default)
			)
			(layer "F.SilkS")
		)
		(fp_rect
			(start -0.508 0.9398)
			(end 0.508 -0.9398)
			(stroke
				(width 0)
				(type default)
			)
			(fill no)
			(layer "F.CrtYd")
		)
		(fp_rect
			(start -0.508 0.9398)
			(end 0.508 -0.9398)
			(stroke
				(width 0)
				(type default)
			)
			(fill no)
			(layer "F.Fab")
		)
		(pad "1" smd custom
			(at 0 -0.4445 90)
			(size 0.1397 0.1397)
			(layers "F.Cu" "F.Mask" "F.Paste")
			(net "HDD_PRSNT_NET12")
			(options
				(clearance outline)
				(anchor circle)
			)
			(primitives
				(gr_poly
					(pts
						(arc
							(start -0.1778 -0.2794)
							(mid -0.249642 -0.249642)
							(end -0.2794 -0.1778)
						)
						(arc
							(start -0.2794 0.1778)
							(mid -0.249642 0.249642)
							(end -0.1778 0.2794)
						)
						(arc
							(start 0.1778 0.2794)
							(mid 0.249642 0.249642)
							(end 0.2794 0.1778)
						)
						(arc
							(start 0.2794 -0.1778)
							(mid 0.249642 -0.249642)
							(end 0.1778 -0.2794)
						)
					)
					(width 0)
					(fill yes)
				)
			)
		)
		(pad "2" smd custom
			(at 0 0.4445 90)
			(size 0.1397 0.1397)
			(layers "F.Cu" "F.Mask" "F.Paste")
			(net "HDD12_LED_B")
			(options
				(clearance outline)
				(anchor circle)
			)
			(primitives
				(gr_poly
					(pts
						(arc
							(start -0.1778 -0.2794)
							(mid -0.249642 -0.249642)
							(end -0.2794 -0.1778)
						)
						(arc
							(start -0.2794 0.1778)
							(mid -0.249642 0.249642)
							(end -0.1778 0.2794)
						)
						(arc
							(start 0.1778 0.2794)
							(mid 0.249642 0.249642)
							(end 0.2794 0.1778)
						)
						(arc
							(start 0.2794 -0.1778)
							(mid 0.249642 -0.249642)
							(end 0.1778 -0.2794)
						)
					)
					(width 0)
					(fill yes)
				)
			)
		)
	)
	(footprint ""
		(layer "F.Cu")
		(at 9.4234 -153.2128 90)
		(property "Reference" "R548"
			(at 0 0 90)
			(layer "F.SilkS")
			(hide yes)
			(effects
				(font
					(size 1.27 1.27)
				)
			)
		)
		(property "Value" "0R2J-2-GP"
			(at 0.064008 -3.993896 90)
			(unlocked yes)
			(layer "F.Fab")
			(hide yes)
			(effects
				(font
					(size 1.016 1.016)
					(thickness 0.1524)
				)
			)
		)
		(property "Device Type" "R402H16"
			(at 0.064008 -5.517896 90)
			(unlocked yes)
			(layer "F.Fab")
			(hide yes)
			(effects
				(font
					(size 1.016 1.016)
					(thickness 0.1524)
				)
			)
		)
		(duplicate_pad_numbers_are_jumpers no)
		(fp_line
			(start 0.508 -0.9398)
			(end -0.508 -0.9398)
			(stroke
				(width 0.1524)
				(type default)
			)
			(layer "F.SilkS")
		)
		(fp_line
			(start -0.508 -0.9398)
			(end -0.508 0.9398)
			(stroke
				(width 0.1524)
				(type default)
			)
			(layer "F.SilkS")
		)
		(fp_rect
			(start -0.508 0.9398)
			(end 0.508 -0.9398)
			(stroke
				(width 0)
				(type default)
			)
			(fill no)
			(layer "F.CrtYd")
		)
		(fp_rect
			(start -0.508 0.9398)
			(end 0.508 -0.9398)
			(stroke
				(width 0)
				(type default)
			)
			(fill no)
			(layer "F.Fab")
		)
		(pad "1" smd custom
			(at 0 -0.4445 90)
			(size 0.1397 0.1397)
			(layers "F.Cu" "F.Mask" "F.Paste")
			(net "I2C_D_SCL_DAMP_B")
			(options
				(clearance outline)
				(anchor circle)
			)
			(primitives
				(gr_poly
					(pts
						(arc
							(start -0.1778 -0.2794)
							(mid -0.249642 -0.249642)
							(end -0.2794 -0.1778)
						)
						(arc
							(start -0.2794 0.1778)
							(mid -0.249642 0.249642)
							(end -0.1778 0.2794)
						)
						(arc
							(start 0.1778 0.2794)
							(mid 0.249642 0.249642)
							(end 0.2794 0.1778)
						)
						(arc
							(start 0.2794 -0.1778)
							(mid 0.249642 -0.249642)
							(end 0.1778 -0.2794)
						)
					)
					(width 0)
					(fill yes)
				)
			)
		)
		(pad "2" smd custom
			(at 0 0.4445 90)
			(size 0.1397 0.1397)
			(layers "F.Cu" "F.Mask" "F.Paste")
			(net "I2C_D_SCL")
			(options
				(clearance outline)
				(anchor circle)
			)
			(primitives
				(gr_poly
					(pts
						(arc
							(start -0.1778 -0.2794)
							(mid -0.249642 -0.249642)
							(end -0.2794 -0.1778)
						)
						(arc
							(start -0.2794 0.1778)
							(mid -0.249642 0.249642)
							(end -0.1778 0.2794)
						)
						(arc
							(start 0.1778 0.2794)
							(mid 0.249642 0.249642)
							(end 0.2794 0.1778)
						)
						(arc
							(start 0.2794 -0.1778)
							(mid 0.249642 -0.249642)
							(end 0.1778 -0.2794)
						)
					)
					(width 0)
					(fill yes)
				)
			)
		)
	)
	(footprint ""
		(layer "F.Cu")
		(at 217.122756 -481.358702)
		(property "Reference" "R111"
			(at 0 0 0)
			(layer "F.SilkS")
			(hide yes)
			(effects
				(font
					(size 1.27 1.27)
				)
			)
		)
		(property "Value" "220R3F-1-GP"
			(at -0.0254 -2.5146 0)
			(unlocked yes)
			(layer "F.Fab")
			(hide yes)
			(effects
				(font
					(size 1.016 1.016)
					(thickness 0.1524)
				)
			)
		)
		(property "Device Type" "R603H22"
			(at -0.0254 -4.0386 0)
			(unlocked yes)
			(layer "F.Fab")
			(hide yes)
			(effects
				(font
					(size 1.016 1.016)
					(thickness 0.1524)
				)
			)
		)
		(duplicate_pad_numbers_are_jumpers no)
		(fp_line
			(start -0.4826 0)
			(end -0.2032 0)
			(stroke
				(width 0.2032)
				(type default)
			)
			(layer "F.SilkS")
		)
		(fp_line
			(start 0.2032 0)
			(end 0.4826 0)
			(stroke
				(width 0.2032)
				(type default)
			)
			(layer "F.SilkS")
		)
		(fp_rect
			(start -0.5842 1.3335)
			(end 0.5842 -1.3335)
			(stroke
				(width 0)
				(type default)
			)
			(fill no)
			(layer "F.CrtYd")
		)
		(fp_rect
			(start -0.5842 1.3335)
			(end 0.5842 -1.3335)
			(stroke
				(width 0)
				(type default)
			)
			(fill no)
			(layer "F.Fab")
		)
		(pad "1" smd custom
			(at 0 -0.762)
			(size 0.2159 0.2159)
			(layers "F.Cu" "F.Mask" "F.Paste")
			(net "HDD_PRSNT_NET0")
			(options
				(clearance outline)
				(anchor circle)
			)
			(primitives
				(gr_poly
					(pts
						(arc
							(start -0.3302 -0.4318)
							(mid -0.402042 -0.402042)
							(end -0.4318 -0.3302)
						)
						(arc
							(start -0.4318 0.3302)
							(mid -0.402042 0.402042)
							(end -0.3302 0.4318)
						)
						(arc
							(start 0.3302 0.4318)
							(mid 0.402042 0.402042)
							(end 0.4318 0.3302)
						)
						(arc
							(start 0.4318 -0.3302)
							(mid 0.402042 -0.402042)
							(end 0.3302 -0.4318)
						)
					)
					(width 0)
					(fill yes)
				)
			)
		)
		(pad "2" smd custom
			(at 0 0.762)
			(size 0.2159 0.2159)
			(layers "F.Cu" "F.Mask" "F.Paste")
			(net "HDD_PRSNT0")
			(options
				(clearance outline)
				(anchor circle)
			)
			(primitives
				(gr_poly
					(pts
						(arc
							(start -0.3302 -0.4318)
							(mid -0.402042 -0.402042)
							(end -0.4318 -0.3302)
						)
						(arc
							(start -0.4318 0.3302)
							(mid -0.402042 0.402042)
							(end -0.3302 0.4318)
						)
						(arc
							(start 0.3302 0.4318)
							(mid 0.402042 0.402042)
							(end 0.4318 0.3302)
						)
						(arc
							(start 0.4318 -0.3302)
							(mid 0.402042 -0.402042)
							(end 0.3302 -0.4318)
						)
					)
					(width 0)
					(fill yes)
				)
			)
		)
	)
	(footprint ""
		(layer "F.Cu")
		(at 79.629 -500.888 180)
		(property "Reference" "R554"
			(at 0 0 180)
			(layer "F.SilkS")
			(hide yes)
			(effects
				(font
					(size 1.27 1.27)
				)
			)
		)
		(property "Value" "200KR2F-L-GP"
			(at 0.064008 -3.993896 180)
			(unlocked yes)
			(layer "F.Fab")
			(hide yes)
			(effects
				(font
					(size 1.016 1.016)
					(thickness 0.1524)
				)
			)
		)
		(property "Device Type" "R402H16"
			(at 0.064008 -5.517896 180)
			(unlocked yes)
			(layer "F.Fab")
			(hide yes)
			(effects
				(font
					(size 1.016 1.016)
					(thickness 0.1524)
				)
			)
		)
		(duplicate_pad_numbers_are_jumpers no)
		(fp_line
			(start 0.508 -0.9398)
			(end -0.508 -0.9398)
			(stroke
				(width 0.1524)
				(type default)
			)
			(layer "F.SilkS")
		)
		(fp_line
			(start -0.508 -0.9398)
			(end -0.508 0.9398)
			(stroke
				(width 0.1524)
				(type default)
			)
			(layer "F.SilkS")
		)
		(fp_rect
			(start -0.508 0.9398)
			(end 0.508 -0.9398)
			(stroke
				(width 0)
				(type default)
			)
			(fill no)
			(layer "F.CrtYd")
		)
		(fp_rect
			(start -0.508 0.9398)
			(end 0.508 -0.9398)
			(stroke
				(width 0)
				(type default)
			)
			(fill no)
			(layer "F.Fab")
		)
		(pad "1" smd custom
			(at 0 -0.4445 180)
			(size 0.1397 0.1397)
			(layers "F.Cu" "F.Mask" "F.Paste")
			(net "SW_HDD5_R")
			(options
				(clearance outline)
				(anchor circle)
			)
			(primitives
				(gr_poly
					(pts
						(arc
							(start -0.1778 -0.2794)
							(mid -0.249642 -0.249642)
							(end -0.2794 -0.1778)
						)
						(arc
							(start -0.2794 0.1778)
							(mid -0.249642 0.249642)
							(end -0.1778 0.2794)
						)
						(arc
							(start 0.1778 0.2794)
							(mid 0.249642 0.249642)
							(end 0.2794 0.1778)
						)
						(arc
							(start 0.2794 -0.1778)
							(mid 0.249642 -0.249642)
							(end 0.1778 -0.2794)
						)
					)
					(width 0)
					(fill yes)
				)
			)
		)
		(pad "2" smd custom
			(at 0 0.4445 180)
			(size 0.1397 0.1397)
			(layers "F.Cu" "F.Mask" "F.Paste")
			(net "SW_HDD5_N")
			(options
				(clearance outline)
				(anchor circle)
			)
			(primitives
				(gr_poly
					(pts
						(arc
							(start -0.1778 -0.2794)
							(mid -0.249642 -0.249642)
							(end -0.2794 -0.1778)
						)
						(arc
							(start -0.2794 0.1778)
							(mid -0.249642 0.249642)
							(end -0.1778 0.2794)
						)
						(arc
							(start 0.1778 0.2794)
							(mid 0.249642 0.249642)
							(end 0.2794 0.1778)
						)
						(arc
							(start 0.2794 -0.1778)
							(mid 0.249642 -0.249642)
							(end 0.1778 -0.2794)
						)
					)
					(width 0)
					(fill yes)
				)
			)
		)
	)
)
